FILE_TYPE = MULTI_PHYS_TABLE;

PART 'SCONN168_ME1016810202011'

{========================================================================================}
:VALUE                      | PART_TYPE | MATERIAL | PART_NUMBER      = STANDARD        | LIFECYCLE      | PART_NUMBER   | JEDEC_TYPE                      | DESCRIPTION                                       | MANUFTR | MANUF_PN          | RD_CMPLS_LVL | CMPLS_LVL | CLASS | DIP_SMD | FROM_PJ     | DATA                      | FP_ECN                 | EE_CHECK_LIST | CREATOR | CREATEDAY  | PSL | STATUS | ESD_CDM | ESD_HBM | ESD_MM | MSD  | PIN_LENGTH_LONG_PIN | PIN_LENGTH_SHORT_PIN ;
{========================================================================================}
 'SCONN168_ME1016810202011' | 'SMLF'    | 'IO'     | 'DFHSG8FR011'(!) = ''              | ''             | 'DFHSG8FR011' |'CON_F168S2H7D_P0-6W2-95_LUH'| 'CONN SMD HOUSING 168P 2R FR(P0.6,H5.35)'         | 'APL'   | 'ME1016810202011' | 'EP(V1)'     | ''        | 'IO'  | ''      | 'F0C-BELL'  | 'APL_ME1016810202011.pdf' | 'ME1016810202011.msg'  | ''            | ''      | '20200615' | ''  | ''     | 'NA'    | 'NA'    | 'NA'   | 'NA' | '56 MILS'           | '36 MILS'           
 'SCONN168_ME1016810202011' | 'SMLF'    | 'EMPTY'  | 'DFHSG8FR011'(!) = ''              | ''             | 'DFHSG8FR011' |'CON_F168S2H7D_P0-6W2-95_LUH'| 'CONN SMD HOUSING 168P 2R FR(P0.6,H5.35)'         | 'APL'   | 'ME1016810202011' | 'EP(V1)'     | ''        | 'IO'  | ''      | 'F0C-BELL'  | 'APL_ME1016810202011.pdf' | 'ME1016810202011.msg'  | ''            | ''      | '20200615' | ''  | ''     | 'NA'    | 'NA'    | 'NA'   | 'NA' | '56 MILS'           | '36 MILS'           
 'SCONN168_ME1016810202011' | 'SMLF'    | 'IO'     | 'SP_DFHSG8FR011'(!) = ''               | ''               | 'DFHSG8FR011' |'G_CON_F168S2H7D_P0-6W2-95_LUH'| 'CONN SMD HOUSING 168P 2R FR(P0.6,H5.35)_FOR SEL' | 'APL'   | 'ME1016810202011' | 'EP(V1)'     | 'EP(V1)'  | 'IO'  | ''      | 'S9B-EASON' | 'APL_ME1016810202011.pdf' | 'ME1016810202011.xlsx' | ''            | ''      | '20230131' | ''  | ''     | ''      | ''      | ''     | ''   | '56 MILS'           | '36 MILS'           
 'SCONN168_ME1016810202011' | 'SMLF'    | 'EMPTY'  | 'SP_DFHSG8FR011'(!) = ''               | ''               | 'DFHSG8FR011' |'G_CON_F168S2H7D_P0-6W2-95_LUH'| 'CONN SMD HOUSING 168P 2R FR(P0.6,H5.35)_FOR SEL' | 'APL'   | 'ME1016810202011' | 'EP(V1)'     | 'EP(V1)'  | 'IO'  | ''      | 'S9B-EASON' | 'APL_ME1016810202011.pdf' | 'ME1016810202011.xlsx' | ''            | ''      | '20230131' | ''  | ''     | ''      | ''      | ''     | ''   | '56 MILS'           | '36 MILS'           

END_PART

END.

